FILE_TYPE = MACRO_DRAWING;
SET COLOR_WIRE YELLOW;
SET COLOR_PROP ORANGE;
SET COLOR_DOT WHITE;
SET COLOR_ARC YELLOW;
SET COLOR_BODY GREEN;
SET COLOR_NOTE PURPLE;
SET PROP_DISPLAY VALUE;
SET PAGE_NUMBER P118;
FORCEADD QUANTA_TITLE_BLOCK_C..1
(0 0);
FORCEPROP 1 LAST CUSTOM_TXT_CDS <NAME_2>
J 0
(-3175 50);
FORCEPROP 1 LAST CUSTOM_TXT_CDS <NAME_1>
J 0
(-3175 175);
FORCEPROP 1 LAST CUSTOM_TXT_CDS <Q_NUMBER>
J 0
(-1403 103);
DISPLAY 1.212766 (-1403 103);
FORCEPROP 1 LAST CUSTOM_TXT_CDS <Q_PROJ>
J 0
(-2382 102);
DISPLAY 1.212766 (-2382 102);
FORCEPROP 1 LAST CUSTOM_TXT_CDS <Q_REV>
J 0
(-184 103);
DISPLAY 1.212766 (-184 103);
FORCEPROP 1 LAST CUSTOM_TXT_CDS <CON_LAST_MODIFIED>
J 0
(-1885 15);
DISPLAY 0.978723 (-1885 15);
FORCEPROP 1 LAST CUSTOM_TXT_CDS <CON_PAGE_NUM> OF <CON_TOTAL_PAGES>
J 0
(-446 18);
DISPLAY 0.978723 (-446 18);
FORCEPROP 1 LAST Q_DEPT BU9
J 1
(-3763 49);
DISPLAY 1.957447 (-3763 49);
PAINT GREEN (-3763 49);
FORCEPROP 1 LAST Q_TITLE SCM MISC
J 0
(-9275 75);
DISPLAY 2.446809 (-9275 75);
PAINT GREEN (-9275 75);
FORCEPROP 1 LAST COMMENT_BODY TRUE
J 0
(12 -13);
DISPLAY 0.978723 (12 -13);
PAINT GREEN (12 -13);
DISPLAY INVISIBLE (12 -13);
FORCEPROP 2 LAST PAGE_BORDER TRUE
J 0
(-7890 5250);
DISPLAY 0.638298 (-7890 5250);
PAINT PINK (-7890 5250);
DISPLAY INVISIBLE (-7890 5250);
FORCEPROP 2 LAST CDS_LIB pure_quanta
J 0
(0 0);
DISPLAY INVISIBLE (0 0);
FORCEPROP 1 LAST CDS_LMAN_SYM_OUTLINE -9475,6775,100,-125
J 0
(0 0);
DISPLAY 0.468085 (0 0);
PAINT GREEN (0 0);
DISPLAY INVISIBLE (0 0);
FORCEPROP 2 LAST CDS_XR_PAGE_TITLE CR-118 : @T6G_MB_LIB.T6G(SCH_1):PAGE118
J 0
(-7890 5250);
DISPLAY 0.638298 (-7890 5250);
PAINT PINK (-7890 5250);
DISPLAY INVISIBLE (-7890 5250);
FORCEPROP 2 LAST CUSTOM_TXT_CDS <XR_PAGE_TITLE>
J 0
(-7890 5250);
DISPLAY 0.638298 (-7890 5250);
PAINT PINK (-7890 5250);
DISPLAY INVISIBLE (-7890 5250);
FORCEPROP 0 LAST CDS_CON_LAST_MODIFIED Wed Mar 09 17:51:07 2022
J 0
(-1885 15);
DISPLAY INVISIBLE (-1885 15);
QUIT
